(kicad_pcb
	(version 20241229)
	(generator "pcbnew")
	(generator_version "9.0")
	(general
		(thickness 1.6)
		(legacy_teardrops no)
	)
	(paper "A4")
	(title_block
		(title "GMSL Deserializer")
		(date "2025-10-09")
		(rev "1.0.4")
		(company "Antmicro Ltd")
		(comment 1 "www.antmicro.com")
		(comment 9 "footprints 113-118 of 235")
	)
	(layers
		(0 "F.Cu" signal)
		(4 "In1.Cu" power)
		(6 "In2.Cu" power)
		(2 "B.Cu" signal)
		(9 "F.Adhes" user "F.Adhesive")
		(11 "B.Adhes" user "B.Adhesive")
		(13 "F.Paste" user)
		(15 "B.Paste" user)
		(5 "F.SilkS" user "F.Silkscreen")
		(7 "B.SilkS" user "B.Silkscreen")
		(1 "F.Mask" user)
		(3 "B.Mask" user)
		(17 "Dwgs.User" user "User.Drawings")
		(19 "Cmts.User" user "User.Comments")
		(21 "Eco1.User" user "User.Eco1")
		(23 "Eco2.User" user "User.Eco2")
		(25 "Edge.Cuts" user)
		(27 "Margin" user)
		(31 "F.CrtYd" user "F.Courtyard")
		(29 "B.CrtYd" user "B.Courtyard")
		(35 "F.Fab" user)
		(33 "B.Fab" user)
	)
	(footprint "antmicro-footprints:C_0402_1005Metric"
		(layer "F.Cu")
		(at 179.498 62.33 -90)
		(descr "Capacitor SMD 0402")
		(tags "capacitor SMD 0402")
		(property "Reference" "C31"
			(at 7.8422 -0.588 90)
			(layer "F.SilkS")
			(effects
				(font
					(size 0.7 0.7)
					(thickness 0.15)
				)
				(justify right bottom)
			)
		)
		(property "Value" "C_100n_0402"
			(at -1.022927 2.155213 90)
			(layer "F.Fab")
			(effects
				(font
					(size 0.7 0.7)
					(thickness 0.15)
				)
				(justify right bottom)
			)
		)
		(property "Datasheet" "https://www.murata.com/products/productdetail?partno=GRM155R61H104KE14%23"
			(at 0 0 270)
			(layer "F.Fab")
			(hide yes)
			(effects
				(font
					(size 1.27 1.27)
					(thickness 0.15)
				)
			)
		)
		(property "Description" "SMD Multilayer Ceramic Capacitor, 0.1 µF, 50 V, 0402 [1005 Metric], ± 10%, X5R, GRM Series"
			(at 0 0 270)
			(layer "F.Fab")
			(hide yes)
			(effects
				(font
					(size 1.27 1.27)
					(thickness 0.15)
				)
			)
		)
		(property "Author" "Antmicro"
			(at 117.168 241.828 0)
			(layer "F.Fab")
			(hide yes)
			(effects
				(font
					(size 1 1)
					(thickness 0.15)
				)
			)
		)
		(property "Dielectric" "X5R"
			(at 117.168 241.828 0)
			(layer "F.Fab")
			(hide yes)
			(effects
				(font
					(size 1 1)
					(thickness 0.15)
				)
			)
		)
		(property "License" "Apache-2.0"
			(at 117.168 241.828 0)
			(layer "F.Fab")
			(hide yes)
			(effects
				(font
					(size 1 1)
					(thickness 0.15)
				)
			)
		)
		(property "MPN" "GRM155R61H104KE14D"
			(at 117.168 241.828 0)
			(layer "F.Fab")
			(hide yes)
			(effects
				(font
					(size 1 1)
					(thickness 0.15)
				)
			)
		)
		(property "Manufacturer" "Murata"
			(at 117.168 241.828 0)
			(layer "F.Fab")
			(hide yes)
			(effects
				(font
					(size 1 1)
					(thickness 0.15)
				)
			)
		)
		(property "Val" "100n"
			(at 117.168 241.828 0)
			(layer "F.Fab")
			(hide yes)
			(effects
				(font
					(size 1 1)
					(thickness 0.15)
				)
			)
		)
		(property "Voltage" "50V"
			(at 117.168 241.828 0)
			(layer "F.Fab")
			(hide yes)
			(effects
				(font
					(size 1 1)
					(thickness 0.15)
				)
			)
		)
		(sheetname "/Connectors/")
		(sheetfile "connectors.kicad_sch")
		(attr smd)
		(fp_rect
			(start -0.925 -0.47)
			(end 0.925 0.47)
			(stroke
				(width 0.05)
				(type default)
			)
			(fill no)
			(layer "F.CrtYd")
		)
		(fp_line
			(start -0.494 0.248)
			(end -0.494 -0.25)
			(stroke
				(width 0.15)
				(type solid)
			)
			(layer "F.Fab")
		)
		(fp_line
			(start 0.504 0.248)
			(end -0.494 0.248)
			(stroke
				(width 0.15)
				(type solid)
			)
			(layer "F.Fab")
		)
		(fp_line
			(start -0.494 -0.25)
			(end 0.504 -0.25)
			(stroke
				(width 0.15)
				(type solid)
			)
			(layer "F.Fab")
		)
		(fp_line
			(start 0.504 -0.25)
			(end 0.504 0.248)
			(stroke
				(width 0.15)
				(type solid)
			)
			(layer "F.Fab")
		)
		(pad "1" smd roundrect
			(at -0.48 0 270)
			(size 0.59 0.64)
			(layers "F.Cu" "F.Mask" "F.Paste")
			(roundrect_rratio 0.25)
			(net 1 "GND")
			(pintype "passive")
		)
		(pad "2" smd roundrect
			(at 0.48 0 270)
			(size 0.59 0.64)
			(layers "F.Cu" "F.Mask" "F.Paste")
			(roundrect_rratio 0.25)
			(net 50 "/Connectors/FFC_3V3")
			(pintype "passive")
		)
	)
	(footprint "antmicro-footprints:C_0402_1005Metric"
		(layer "F.Cu")
		(at 180.514 62.354 -90)
		(descr "Capacitor SMD 0402")
		(tags "capacitor SMD 0402")
		(property "Reference" "C58"
			(at 7.9242 -0.592 90)
			(layer "F.SilkS")
			(effects
				(font
					(size 0.7 0.7)
					(thickness 0.15)
				)
				(justify right bottom)
			)
		)
		(property "Value" "C_1u_0402"
			(at -1.022927 2.155213 90)
			(layer "F.Fab")
			(effects
				(font
					(size 0.7 0.7)
					(thickness 0.15)
				)
				(justify right bottom)
			)
		)
		(property "Datasheet" "https://product.tdk.com/en/search/capacitor/ceramic/mlcc/info?part_no=C1005X6S1A105K050BC"
			(at 0 0 270)
			(layer "F.Fab")
			(hide yes)
			(effects
				(font
					(size 1.27 1.27)
					(thickness 0.15)
				)
			)
		)
		(property "Description" "SMD Multilayer Ceramic Capacitor, 1 µF, 10 V, 0402 [1005 Metric], ± 10%, X6S, C"
			(at 0 0 270)
			(layer "F.Fab")
			(hide yes)
			(effects
				(font
					(size 1.27 1.27)
					(thickness 0.15)
				)
			)
		)
		(property "Author" "Antmicro"
			(at 118.16 242.868 0)
			(layer "F.Fab")
			(hide yes)
			(effects
				(font
					(size 1 1)
					(thickness 0.15)
				)
			)
		)
		(property "Dielectric" ""
			(at 118.16 242.868 0)
			(layer "F.Fab")
			(hide yes)
			(effects
				(font
					(size 1 1)
					(thickness 0.15)
				)
			)
		)
		(property "License" "Apache-2.0"
			(at 118.16 242.868 0)
			(layer "F.Fab")
			(hide yes)
			(effects
				(font
					(size 1 1)
					(thickness 0.15)
				)
			)
		)
		(property "MPN" "C1005X6S1A105K050BC"
			(at 118.16 242.868 0)
			(layer "F.Fab")
			(hide yes)
			(effects
				(font
					(size 1 1)
					(thickness 0.15)
				)
			)
		)
		(property "Manufacturer" "TDK"
			(at 118.16 242.868 0)
			(layer "F.Fab")
			(hide yes)
			(effects
				(font
					(size 1 1)
					(thickness 0.15)
				)
			)
		)
		(property "Val" "1u"
			(at 118.16 242.868 0)
			(layer "F.Fab")
			(hide yes)
			(effects
				(font
					(size 1 1)
					(thickness 0.15)
				)
			)
		)
		(property "Voltage" ""
			(at 118.16 242.868 0)
			(layer "F.Fab")
			(hide yes)
			(effects
				(font
					(size 1 1)
					(thickness 0.15)
				)
			)
		)
		(sheetname "/Connectors/")
		(sheetfile "connectors.kicad_sch")
		(attr smd)
		(fp_rect
			(start -0.925 -0.47)
			(end 0.925 0.47)
			(stroke
				(width 0.05)
				(type default)
			)
			(fill no)
			(layer "F.CrtYd")
		)
		(fp_line
			(start -0.494 0.248)
			(end -0.494 -0.25)
			(stroke
				(width 0.15)
				(type solid)
			)
			(layer "F.Fab")
		)
		(fp_line
			(start 0.504 0.248)
			(end -0.494 0.248)
			(stroke
				(width 0.15)
				(type solid)
			)
			(layer "F.Fab")
		)
		(fp_line
			(start -0.494 -0.25)
			(end 0.504 -0.25)
			(stroke
				(width 0.15)
				(type solid)
			)
			(layer "F.Fab")
		)
		(fp_line
			(start 0.504 -0.25)
			(end 0.504 0.248)
			(stroke
				(width 0.15)
				(type solid)
			)
			(layer "F.Fab")
		)
		(pad "1" smd roundrect
			(at -0.48 0 270)
			(size 0.59 0.64)
			(layers "F.Cu" "F.Mask" "F.Paste")
			(roundrect_rratio 0.25)
			(net 1 "GND")
			(pintype "passive")
		)
		(pad "2" smd roundrect
			(at 0.48 0 270)
			(size 0.59 0.64)
			(layers "F.Cu" "F.Mask" "F.Paste")
			(roundrect_rratio 0.25)
			(net 50 "/Connectors/FFC_3V3")
			(pintype "passive")
		)
	)
	(footprint "antmicro-footprints:TP_SMD_0.75mm"
		(layer "F.Cu")
		(at 156.972 97.89)
		(property "Reference" "TP8"
			(at 0 -0.6 0)
			(layer "F.SilkS")
			(hide yes)
			(effects
				(font
					(size 0.7 0.7)
					(thickness 0.15)
				)
				(justify left bottom)
			)
		)
		(property "Value" "TP_0.75mm_SMD"
			(at 0 1.2 0)
			(layer "F.Fab")
			(effects
				(font
					(size 0.7 0.7)
					(thickness 0.15)
				)
				(justify left bottom)
			)
		)
		(property "Description" "SMT test point"
			(at 0 0 0)
			(layer "F.Fab")
			(hide yes)
			(effects
				(font
					(size 1.27 1.27)
					(thickness 0.15)
				)
			)
		)
		(property "Author" "Antmicro"
			(at 0 0 0)
			(layer "F.Fab")
			(hide yes)
			(effects
				(font
					(size 1 1)
					(thickness 0.15)
				)
			)
		)
		(property "License" "Apache-2.0"
			(at 0 0 0)
			(layer "F.Fab")
			(hide yes)
			(effects
				(font
					(size 1 1)
					(thickness 0.15)
				)
			)
		)
		(property "MPN" ""
			(at 0 0 0)
			(layer "F.Fab")
			(hide yes)
			(effects
				(font
					(size 1 1)
					(thickness 0.15)
				)
			)
		)
		(property "Manufacturer" ""
			(at 0 0 0)
			(layer "F.Fab")
			(hide yes)
			(effects
				(font
					(size 1 1)
					(thickness 0.15)
				)
			)
		)
		(sheetname "/Connectors/")
		(sheetfile "connectors.kicad_sch")
		(fp_circle
			(center 0 0)
			(end 0.475 0)
			(stroke
				(width 0.05)
				(type default)
			)
			(fill no)
			(layer "F.CrtYd")
		)
		(pad "1" smd circle
			(at 0 0)
			(size 0.75 0.75)
			(layers "F.Cu" "F.Mask")
			(net 50 "/Connectors/FFC_3V3")
			(pinfunction "1")
			(pintype "passive")
		)
	)
	(footprint "antmicro-footprints:R_0402_1005Metric"
		(layer "F.Cu")
		(at 127.255 61.976 90)
		(descr "Resistor SMD 0402")
		(tags "resistor SMD 0402")
		(property "Reference" "R19"
			(at -1.1405 1.27 90)
			(layer "F.SilkS")
			(effects
				(font
					(size 0.7 0.7)
					(thickness 0.15)
				)
				(justify left bottom)
			)
		)
		(property "Value" "R_5k1_0402"
			(at -1.011843 1.772047 90)
			(layer "F.Fab")
			(effects
				(font
					(size 0.7 0.7)
					(thickness 0.15)
				)
				(justify left bottom)
			)
		)
		(property "Datasheet" "https://www.bourns.com/docs/product-datasheets/cr.pdf"
			(at 0 0 90)
			(layer "F.Fab")
			(hide yes)
			(effects
				(font
					(size 1.27 1.27)
					(thickness 0.15)
				)
			)
		)
		(property "Description" "SMD Chip Resistor, 5.1 kohm, ± 1%, 63 mW, 0402 [1005 Metric], Thick Film, General Purpose"
			(at 0 0 90)
			(layer "F.Fab")
			(hide yes)
			(effects
				(font
					(size 1.27 1.27)
					(thickness 0.15)
				)
			)
		)
		(property "Author" "Antmicro"
			(at 189.231 -65.279 0)
			(layer "F.Fab")
			(hide yes)
			(effects
				(font
					(size 1 1)
					(thickness 0.15)
				)
			)
		)
		(property "License" "Apache-2.0"
			(at 189.231 -65.279 0)
			(layer "F.Fab")
			(hide yes)
			(effects
				(font
					(size 1 1)
					(thickness 0.15)
				)
			)
		)
		(property "MPN" "CR0402-FX-5101GLF"
			(at 189.231 -65.279 0)
			(layer "F.Fab")
			(hide yes)
			(effects
				(font
					(size 1 1)
					(thickness 0.15)
				)
			)
		)
		(property "Manufacturer" "Bourns"
			(at 189.231 -65.279 0)
			(layer "F.Fab")
			(hide yes)
			(effects
				(font
					(size 1 1)
					(thickness 0.15)
				)
			)
		)
		(property "Tolerance" "1%"
			(at 189.231 -65.279 0)
			(layer "F.Fab")
			(hide yes)
			(effects
				(font
					(size 1 1)
					(thickness 0.15)
				)
			)
		)
		(property "Val" "5k1"
			(at 189.231 -65.279 0)
			(layer "F.Fab")
			(hide yes)
			(effects
				(font
					(size 1 1)
					(thickness 0.15)
				)
			)
		)
		(sheetname "/Power/")
		(sheetfile "power.kicad_sch")
		(attr smd)
		(fp_rect
			(start -0.925 -0.47)
			(end 0.925 0.47)
			(stroke
				(width 0.05)
				(type default)
			)
			(fill no)
			(layer "F.CrtYd")
		)
		(fp_rect
			(start -0.5 -0.25)
			(end 0.5 0.25)
			(stroke
				(width 0.15)
				(type solid)
			)
			(fill no)
			(layer "F.Fab")
		)
		(pad "1" smd roundrect
			(at -0.48 0 90)
			(size 0.59 0.64)
			(layers "F.Cu" "F.Mask" "F.Paste")
			(roundrect_rratio 0.25)
			(net 4 "+12V")
			(pintype "passive")
		)
		(pad "2" smd roundrect
			(at 0.48 0 90)
			(size 0.59 0.64)
			(layers "F.Cu" "F.Mask" "F.Paste")
			(roundrect_rratio 0.25)
			(net 51 "Net-(L1-Pad2)")
			(pintype "passive")
		)
	)
	(footprint "antmicro-footprints:C_0402_1005Metric"
		(layer "F.Cu")
		(at 173.91 61.722 90)
		(descr "Capacitor SMD 0402")
		(tags "capacitor SMD 0402")
		(property "Reference" "C26"
			(at 0.830095 0.424135 90)
			(layer "F.SilkS")
			(effects
				(font
					(size 0.7 0.7)
					(thickness 0.15)
				)
				(justify left bottom)
			)
		)
		(property "Value" "C_100n_0402"
			(at -1.022927 2.155213 90)
			(layer "F.Fab")
			(effects
				(font
					(size 0.7 0.7)
					(thickness 0.15)
				)
				(justify left bottom)
			)
		)
		(property "Datasheet" "https://www.murata.com/products/productdetail?partno=GRM155R61H104KE14%23"
			(at 0 0 90)
			(layer "F.Fab")
			(hide yes)
			(effects
				(font
					(size 1.27 1.27)
					(thickness 0.15)
				)
			)
		)
		(property "Description" "SMD Multilayer Ceramic Capacitor, 0.1 µF, 50 V, 0402 [1005 Metric], ± 10%, X5R, GRM Series"
			(at 0 0 90)
			(layer "F.Fab")
			(hide yes)
			(effects
				(font
					(size 1.27 1.27)
					(thickness 0.15)
				)
			)
		)
		(property "Author" "Antmicro"
			(at 235.632 -112.188 0)
			(layer "F.Fab")
			(hide yes)
			(effects
				(font
					(size 1 1)
					(thickness 0.15)
				)
			)
		)
		(property "Dielectric" "X5R"
			(at 235.632 -112.188 0)
			(layer "F.Fab")
			(hide yes)
			(effects
				(font
					(size 1 1)
					(thickness 0.15)
				)
			)
		)
		(property "License" "Apache-2.0"
			(at 235.632 -112.188 0)
			(layer "F.Fab")
			(hide yes)
			(effects
				(font
					(size 1 1)
					(thickness 0.15)
				)
			)
		)
		(property "MPN" "GRM155R61H104KE14D"
			(at 235.632 -112.188 0)
			(layer "F.Fab")
			(hide yes)
			(effects
				(font
					(size 1 1)
					(thickness 0.15)
				)
			)
		)
		(property "Manufacturer" "Murata"
			(at 235.632 -112.188 0)
			(layer "F.Fab")
			(hide yes)
			(effects
				(font
					(size 1 1)
					(thickness 0.15)
				)
			)
		)
		(property "Val" "100n"
			(at 235.632 -112.188 0)
			(layer "F.Fab")
			(hide yes)
			(effects
				(font
					(size 1 1)
					(thickness 0.15)
				)
			)
		)
		(property "Voltage" "50V"
			(at 235.632 -112.188 0)
			(layer "F.Fab")
			(hide yes)
			(effects
				(font
					(size 1 1)
					(thickness 0.15)
				)
			)
		)
		(sheetname "/Connectors/")
		(sheetfile "connectors.kicad_sch")
		(attr smd)
		(fp_rect
			(start -0.925 -0.47)
			(end 0.925 0.47)
			(stroke
				(width 0.05)
				(type default)
			)
			(fill no)
			(layer "F.CrtYd")
		)
		(fp_line
			(start 0.504 -0.25)
			(end 0.504 0.248)
			(stroke
				(width 0.15)
				(type solid)
			)
			(layer "F.Fab")
		)
		(fp_line
			(start -0.494 -0.25)
			(end 0.504 -0.25)
			(stroke
				(width 0.15)
				(type solid)
			)
			(layer "F.Fab")
		)
		(fp_line
			(start 0.504 0.248)
			(end -0.494 0.248)
			(stroke
				(width 0.15)
				(type solid)
			)
			(layer "F.Fab")
		)
		(fp_line
			(start -0.494 0.248)
			(end -0.494 -0.25)
			(stroke
				(width 0.15)
				(type solid)
			)
			(layer "F.Fab")
		)
		(pad "1" smd roundrect
			(at -0.48 0 90)
			(size 0.59 0.64)
			(layers "F.Cu" "F.Mask" "F.Paste")
			(roundrect_rratio 0.25)
			(net 1 "GND")
			(pintype "passive")
		)
		(pad "2" smd roundrect
			(at 0.48 0 90)
			(size 0.59 0.64)
			(layers "F.Cu" "F.Mask" "F.Paste")
			(roundrect_rratio 0.25)
			(net 3 "+1V8")
			(pintype "passive")
		)
	)
	(footprint "antmicro-footprints:Vishay_PowerPAK_1212-8_Single"
		(layer "F.Cu")
		(at 174.752 56.134 90)
		(descr "PowerPAK 1212-8 Single")
		(tags "Vishay PowerPAK 1212-8 Single")
		(property "Reference" "Q2"
			(at 1.957953 0.923594 180)
			(layer "F.SilkS")
			(effects
				(font
					(size 0.7 0.7)
					(thickness 0.15)
				)
				(justify left bottom)
			)
		)
		(property "Value" "SQS401EN-T1_BE3"
			(at 0 2.7 90)
			(layer "F.Fab")
			(effects
				(font
					(size 0.7 0.7)
					(thickness 0.15)
				)
				(justify left bottom)
			)
		)
		(property "Datasheet" "https://www.vishay.com/docs/65529/sqs401en.pdf"
			(at 0 0 90)
			(layer "F.Fab")
			(hide yes)
			(effects
				(font
					(size 1.27 1.27)
					(thickness 0.15)
				)
			)
		)
		(property "Description" "MOSFET, P Channel, 40 V, 16A, 0.047 ohm, PowerPAK 1212-8, Surface Mount"
			(at 0 0 90)
			(layer "F.Fab")
			(hide yes)
			(effects
				(font
					(size 1.27 1.27)
					(thickness 0.15)
				)
			)
		)
		(property "Author" "Antmicro"
			(at 230.886 -118.618 0)
			(layer "F.Fab")
			(hide yes)
			(effects
				(font
					(size 1 1)
					(thickness 0.15)
				)
			)
		)
		(property "License" "Apache-2.0"
			(at 230.886 -118.618 0)
			(layer "F.Fab")
			(hide yes)
			(effects
				(font
					(size 1 1)
					(thickness 0.15)
				)
			)
		)
		(property "MPN" "SQS401EN-T1_BE3"
			(at 230.886 -118.618 0)
			(layer "F.Fab")
			(hide yes)
			(effects
				(font
					(size 1 1)
					(thickness 0.15)
				)
			)
		)
		(property "Manufacturer" "Vishay"
			(at 230.886 -118.618 0)
			(layer "F.Fab")
			(hide yes)
			(effects
				(font
					(size 1 1)
					(thickness 0.15)
				)
			)
		)
		(sheetname "/Power/")
		(sheetfile "power.kicad_sch")
		(attr smd)
		(fp_line
			(start 1.648 -1.651)
			(end 1.648 -1.317)
			(stroke
				(width 0.15)
				(type solid)
			)
			(layer "F.SilkS")
		)
		(fp_line
			(start -1.651 -1.651)
			(end 1.648 -1.651)
			(stroke
				(width 0.15)
				(type solid)
			)
			(layer "F.SilkS")
		)
		(fp_line
			(start -1.651 -1.651)
			(end -1.651 -1.317)
			(stroke
				(width 0.15)
				(type solid)
			)
			(layer "F.SilkS")
		)
		(fp_line
			(start 1.634 1.3)
			(end 1.634 1.634)
			(stroke
				(width 0.15)
				(type solid)
			)
			(layer "F.SilkS")
		)
		(fp_line
			(start -1.635 1.3)
			(end -1.635 1.634)
			(stroke
				(width 0.15)
				(type solid)
			)
			(layer "F.SilkS")
		)
		(fp_line
			(start -1.635 1.634)
			(end 1.634 1.634)
			(stroke
				(width 0.15)
				(type solid)
			)
			(layer "F.SilkS")
		)
		(fp_circle
			(center -1.9 -1.4)
			(end -1.85 -1.4)
			(stroke
				(width 0.15)
				(type solid)
			)
			(fill yes)
			(layer "F.SilkS")
		)
		(fp_rect
			(start -2 -1.8)
			(end 2 1.798)
			(stroke
				(width 0.05)
				(type solid)
			)
			(fill no)
			(layer "F.CrtYd")
		)
		(fp_line
			(start -1.6425 -1.4175)
			(end -1.4175 -1.6425)
			(stroke
				(width 0.15)
				(type solid)
			)
			(layer "F.Fab")
		)
		(fp_rect
			(start -1.651 -1.651)
			(end 1.648 1.648)
			(stroke
				(width 0.15)
				(type solid)
			)
			(fill no)
			(layer "F.Fab")
		)
		(pad "1" smd rect
			(at -1.436 -0.99 90)
			(size 0.99 0.405)
			(layers "F.Cu" "F.Mask" "F.Paste")
			(net 4 "+12V")
			(pinfunction "S")
			(pintype "passive")
		)
		(pad "2" smd rect
			(at -1.436 -0.332 90)
			(size 0.99 0.405)
			(layers "F.Cu" "F.Mask" "F.Paste")
			(net 4 "+12V")
			(pinfunction "S")
			(pintype "passive")
		)
		(pad "3" smd rect
			(at -1.436 0.33 90)
			(size 0.99 0.405)
			(layers "F.Cu" "F.Mask" "F.Paste")
			(net 4 "+12V")
			(pinfunction "S")
			(pintype "passive")
		)
		(pad "4" smd rect
			(at -1.436 0.988 90)
			(size 0.99 0.405)
			(layers "F.Cu" "F.Mask" "F.Paste")
			(net 127 "Net-(Q2-G)")
			(pinfunction "G")
			(pintype "input")
		)
		(pad "5" smd custom
			(at 0.557 0 90)
			(size 1.725 2.235)
			(layers "F.Cu" "F.Mask" "F.Paste")
			(net 118 "/Connectors/DC_IN")
			(pinfunction "D")
			(pintype "passive")
			(zone_connect 2)
			(options
				(clearance outline)
				(anchor rect)
			)
			(primitives
				(gr_poly
					(pts
						(xy 0.8625 0.1275) (xy 0.8625 -0.1275) (xy 1.3725 -0.1275) (xy 1.3725 -0.5325) (xy 0.8625 -0.5325)
						(xy 0.8625 -0.7875) (xy 1.3725 -0.7875) (xy 1.3725 -1.195) (xy 0.6125 -1.195) (xy 0.6125 1.195)
						(xy 1.3725 1.195) (xy 1.3725 0.7875) (xy 0.8625 0.7875) (xy 0.8625 0.5325) (xy 1.3725 0.5325)
						(xy 1.3725 0.1275)
					)
					(width 0)
					(fill yes)
				)
			)
		)
	)
)
